G04 ================== begin FILE IDENTIFICATION RECORD ==================*
G04 Layout Name:  15968-1a.brd*
G04 Film Name:    P_OUTLINE*
G04 File Format:  Gerber RS274X*
G04 File Origin:  Cadence Allegro 16.5-S058*
G04 Origin Date:  Fri Oct 14 10:23:18 2016*
G04 *
G04 Layer:  BOARD GEOMETRY/PANEL_OUTLINE*
G04 *
G04 Offset:    (0.00 0.00)*
G04 Mirror:    No*
G04 Mode:      Positive*
G04 Rotation:  0*
G04 FullContactRelief:  No*
G04 UndefLineWidth:     6.00*
G04 ================== end FILE IDENTIFICATION RECORD ====================*
%FSLAX35Y35*MOIN*%
%IR0*IPPOS*OFA0.00000B0.00000*MIA0B0*SFA1.00000B1.00000*%
%ADD10C,.005*%
G75*
%LPD*%
G75*
G54D10*
G01X-21653Y-58346D02*
G03X-6653Y-73346I15000J0D01*
G01X65080D02*
X-6653D01*
G01X9506Y0D02*
X69017D01*
G01X6722Y1153D02*
G03X9506Y0I2784J2784D01*
G01X1154Y6721D02*
X6722Y1153D01*
G01X1Y9505D02*
G03X1154Y6721I3937J0D01*
G01X1Y238051D02*
Y9505D01*
G01Y238051D02*
Y9505D01*
G01X-21653Y238051D02*
Y9505D01*
G01X1D02*
G03X1154Y6721I3937J0D01*
G01X-7873Y9505D02*
G03X-4414Y1153I11811J-1D01*
G01X1154Y6721D02*
X6722Y1153D01*
G01X-4414D02*
X1154Y-4415D01*
G01X6722Y1153D02*
G03X9506Y0I2784J2784D01*
G01X1154Y-4415D02*
G03X9506Y-7874I8351J8352D01*
G01Y0D02*
X69017D01*
G01X9506Y-7874D02*
X14917D01*
G01X-21653Y9505D02*
Y-58346D01*
G01X14917Y-7874D02*
G03Y0I0J3937D01*
G01X-7873Y50852D02*
Y9505D01*
G01Y81561D02*
G03X1I3937J-1D01*
G01Y50852D02*
G03X-7873I-3937J0D01*
G01Y186482D02*
Y81561D01*
G01X13443Y249862D02*
X611812D01*
G01X10659Y251015D02*
G03X13443Y249862I2784J2784D01*
G01X1154Y260520D02*
X10659Y251015D01*
G01X3938Y241988D02*
G03X1Y238051I0J-3937D01*
G01X602307Y241988D02*
X3938D01*
G01X602307D02*
X3938D01*
G01D02*
G03X1Y238051I0J-3937D01*
G01X-7873D02*
Y217191D01*
G01X1154Y260520D02*
X10659Y251015D01*
G01D02*
G03X13443Y249862I2784J2784D01*
G01D02*
X611812D01*
G01X-21653Y238051D02*
Y534327D01*
G01X-7873Y238051D02*
Y263304D01*
G01Y217191D02*
G03X1I3937J-1D01*
G01Y186482D02*
G03X-7873I-3937J0D01*
G01X1Y263304D02*
G03X1154Y260520I3937J0D01*
G01X1Y328602D02*
Y263304D01*
G01X3938Y332539D02*
G03X1Y328602I0J-3937D01*
G01X53151Y332539D02*
X3938D01*
G01X53151D02*
X3938D01*
G01D02*
G03X1Y328602I0J-3937D01*
G01X3938Y340413D02*
G03X-7873Y328602I0J-11811D01*
G01X1D02*
Y263304D01*
G01X-7873Y328602D02*
Y263304D01*
G01X1D02*
G03X1154Y260520I3937J0D01*
G01X10965Y332539D02*
G03Y340413I0J3937D01*
G01D02*
X3938D01*
G01X-6653Y565196D02*
G03X-21653Y550196I0J-15000D01*
G01X67796Y565196D02*
X-6653D01*
G01X-21653Y542201D02*
Y550196D01*
G01Y534327D02*
G03Y542201I0J3937D01*
G01X74922Y-73346D02*
X175828D01*
G01X72954Y-71378D02*
X74922Y-73346D01*
G01X72954Y-3937D02*
Y-71378D01*
G01X65080Y-7874D02*
Y-71772D01*
G01D02*
Y-73346D01*
G01X72954Y-3937D02*
G03X69017Y0I-3937J0D01*
G01X72954Y-3937D02*
G03X69017Y0I-3937J0D01*
G01X45626D02*
G03Y-7874I0J-3937D01*
G01D02*
X65080D01*
G01X51397Y241988D02*
G03Y249862I0J3937D01*
G01X93906D02*
G03Y241988I0J-3937D01*
G01X53151Y332539D02*
G03X57088Y336476I0J3937D01*
G01Y482345D02*
Y336476D01*
G01Y482345D02*
Y336476D01*
G01X53151Y332539D02*
G03X57088Y336476I0J3937D01*
G01X41674Y340413D02*
G03Y332539I0J-3937D01*
G01X49214Y340413D02*
X41674D01*
G01X49214Y442487D02*
Y340413D01*
G01X67796Y565196D02*
Y499724D01*
G01X75670Y563228D02*
Y495787D01*
G01X58241Y485129D02*
G03X57088Y482345I2784J-2784D01*
G01X63808Y490697D02*
X58241Y485129D01*
G01X66592Y491850D02*
G03X63808Y490697I0J-3937D01*
G01X71733Y491850D02*
X66592D01*
G01X71733D02*
G03X75670Y495787I0J3937D01*
G01X67796Y499724D02*
X66592D01*
G01Y491850D02*
G03X63808Y490697I0J-3937D01*
G01X66592Y499724D02*
G03X58240Y496265I-1J-11811D01*
G01X63808Y490697D02*
X58241Y485129D01*
G01X58240Y496264D02*
X52673Y490696D01*
G01X58241Y485129D02*
G03X57088Y482345I2784J-2784D01*
G01X52673Y490697D02*
G03X49214Y482343I8352J-8351D01*
G01Y482345D02*
Y473195D01*
G01X57088Y442487D02*
G03X49214I-3937J-1D01*
G01Y473195D02*
G03X57088I3937J0D01*
G01X77639Y565196D02*
X75670Y563228D01*
G01X173111Y565196D02*
X77639D01*
G01X177796Y-71378D02*
Y-52874D01*
G01X175828Y-73346D02*
X177796Y-71378D01*
G01X187245Y-52874D02*
G03X177796I-4725J0D01*
G01X175080Y563228D02*
X173111Y565196D01*
G01X175080Y534488D02*
Y563228D01*
G01Y534488D02*
G03X175867Y533700I787J-1D01*
G01X209529D02*
X175867D01*
G01X189214Y-73346D02*
X403466D01*
G01X187245Y-71378D02*
X189214Y-73346D01*
G01X187245Y-52874D02*
Y-71378D01*
G01X209529Y533700D02*
G03X210316Y534488I0J787D01*
G01Y563228D02*
Y534488D01*
G01X212284Y565196D02*
X210316Y563228D01*
G01X426536Y565196D02*
X212284D01*
G01X405434Y-71378D02*
Y-42638D01*
G01X403466Y-73346D02*
X405434Y-71378D01*
G01X406221Y-41850D02*
X439883D01*
G01X406221D02*
G03X405434Y-42638I1J-788D01*
G01X428505Y563228D02*
X426536Y565196D01*
G01X442639Y-73346D02*
X538111D01*
G01X440670Y-71378D02*
X442639Y-73346D01*
G01X440670Y-42638D02*
Y-71378D01*
G01Y-42638D02*
G03X439883Y-41850I-787J1D01*
G01X428504Y544723D02*
Y563227D01*
G01Y544723D02*
G03X437953I4724J0D01*
G01Y563227D02*
Y544723D01*
G01X428505Y544724D02*
Y563228D01*
G01Y544724D02*
G03X437954I4725J0D01*
G01Y563228D02*
Y544724D01*
G01X439922Y565196D02*
X437954Y563228D01*
G01X540828Y565196D02*
X439922D01*
G01X547954Y-73346D02*
X622403D01*
G01X547954D02*
Y-7874D01*
G01X540080Y-71378D02*
Y-3937D01*
G01X538111Y-73346D02*
X540080Y-71378D01*
G01X558662Y9505D02*
Y155374D01*
G01X557509Y6721D02*
G03X558662Y9505I-2784J2784D01*
G01X551942Y1153D02*
X557509Y6721D01*
G01X549158Y0D02*
G03X551942Y1153I0J3937D01*
G01X544017Y0D02*
X549158D01*
G01X544017D02*
G03X540080Y-3937I0J-3937D01*
G01X547954Y-7874D02*
X549158D01*
G01Y0D02*
G03X551942Y1153I0J3937D01*
G01X549158Y-7875D02*
G03X557510Y-4415I0J11811D01*
G01X551942Y1153D02*
X557509Y6721D01*
G01X557510Y-4414D02*
X563077Y1154D01*
G01X557509Y6721D02*
G03X558662Y9505I-2784J2784D01*
G01X563077Y1153D02*
G03X566536Y9507I-8352J8351D01*
G01X558662Y9505D02*
Y155374D01*
G01X566536Y9505D02*
Y18655D01*
G01D02*
G03X558662I-3937J-1D01*
G01Y49363D02*
G03X566536I3937J0D01*
G01D02*
Y151437D01*
G01X562599Y159311D02*
X611812D01*
G01X562599D02*
G03X558662Y155374I0J-3937D01*
G01X562599Y159311D02*
G03X558662Y155374I0J-3937D01*
G01X562599Y159311D02*
X611812D01*
G01X566536Y151437D02*
X574076D01*
G01D02*
G03Y159311I0J3937D01*
G01X564353Y249862D02*
G03Y241988I0J-3937D01*
G01X521844D02*
G03Y249862I0J3937D01*
G01X542796Y495787D02*
Y563228D01*
G01Y495787D02*
G03X546733Y491850I3937J0D01*
G01X606244D02*
X546733D01*
G01X606244D02*
X546733D01*
G01X542796Y495787D02*
G03X546733Y491850I3937J0D01*
G01X550670Y499724D02*
Y563622D01*
G01X570124Y491850D02*
G03Y499724I0J3937D01*
G01D02*
X550670D01*
G01Y565196D02*
X622403D01*
G01X542796Y563228D02*
X540828Y565196D01*
G01X550670Y563622D02*
Y565196D01*
G01X622403Y-73346D02*
G03X637403Y-58346I0J15000D01*
G01Y253799D02*
Y-58346D01*
G01X615749Y163248D02*
Y228546D01*
G01X611812Y159311D02*
G03X615749Y163248I0J3937D01*
G01X611812Y159311D02*
G03X615749Y163248I0J3937D01*
G01X611812Y151437D02*
G03X623623Y163248I0J11811D01*
G01X615749D02*
Y228546D01*
G01X623623Y163248D02*
Y228546D01*
G01X604785Y159311D02*
G03Y151437I0J-3937D01*
G01D02*
X611812D01*
G01X615749Y253799D02*
Y482345D01*
G01X611812Y249862D02*
G03X615749Y253799I0J3937D01*
G01X605091Y240835D02*
G03X602307Y241988I-2784J-2784D01*
G01X614596Y231330D02*
X605091Y240835D01*
G01X615749Y228546D02*
G03X614596Y231330I-3937J0D01*
G01X615749Y228546D02*
G03X614596Y231330I-3937J0D01*
G01D02*
X605091Y240835D01*
G01D02*
G03X602307Y241988I-2784J-2784D01*
G01X611812Y249862D02*
G03X615749Y253799I0J3937D01*
G01D02*
Y482345D01*
G01X623623Y253799D02*
Y274659D01*
G01X637403Y253799D02*
Y482345D01*
G01X623623Y228546D02*
Y253799D01*
G01Y274659D02*
G03X615749I-3937J0D01*
G01Y305368D02*
G03X623623I3937J0D01*
G01D02*
Y410289D01*
G01D02*
G03X615749I-3937J0D01*
G01X609028Y490697D02*
G03X606244Y491850I-2784J-2784D01*
G01X614596Y485129D02*
X609028Y490697D01*
G01X615749Y482345D02*
G03X614596Y485129I-3937J0D01*
G01X615749Y482345D02*
G03X614596Y485129I-3937J0D01*
G01X623623Y482345D02*
G03X620164Y490697I-11811J1D01*
G01X614596Y485129D02*
X609028Y490697D01*
G01X620164D02*
X614596Y496265D01*
G01X609028Y490697D02*
G03X606244Y491850I-2784J-2784D01*
G01X614596Y496265D02*
G03X606244Y499724I-8351J-8352D01*
G01D02*
X600833D01*
G01X637403Y482345D02*
Y550196D01*
G01X600833Y499724D02*
G03Y491850I0J-3937D01*
G01X615749Y440998D02*
G03X623623I3937J0D01*
G01D02*
Y482345D01*
G01X637403Y550196D02*
G03X622403Y565196I-15000J0D01*
M02*
